# S9S_MB_2U (Grand Teton) — schematic netlist excerpt (pin names and nets, part order shuffled) for the footprints in the layout excerpt that follows; sources: Cadence DE-HDL packaged netlist, KiCad conversion of 03242023_DA0F0TMBIJ0_F0T_Motherboard_J_brd_V01_OCP.brd

X24  TP_TDR_4P_FTS  TP_TDR_4P_DIP EMPTY  pkg TH  page 309
  S1  = TDR_DIFF_100_BOT_DN
  P1  = T1_GND
  P2  = T1_GND
  S2  = TDR_DIFF_100_BOT_DP

C2315  Q_CAP  0.1UF 25V 10% EMPTY  pkg 0402  page 196 : A = P3V3_AUX_USB_HUB_2 ; B = GND

(kicad_pcb
	(version 20260206)
	(generator "pcbnew")
	(generator_version "10.0")
	(general
		(thickness 1.6)
		(legacy_teardrops no)
	)
	(paper "A4")
	(title_block
		(title "03242023_DA0F0TMBIJ0_F0T_Motherboard_J_brd_V01_OCP.brd")
		(comment 1 "Grand Teton / footprints 5790-5791 of 6105")
	)
	(layers
		(0 "F.Cu" signal "TOP")
		(4 "In1.Cu" signal "GND")
		(6 "In2.Cu" signal "IN1")
		(8 "In3.Cu" signal "GND1")
		(10 "In4.Cu" signal "IN2")
		(12 "In5.Cu" signal "GND2")
		(14 "In6.Cu" signal "IN3")
		(16 "In7.Cu" signal "GND3")
		(18 "In8.Cu" signal "VCC")
		(20 "In9.Cu" signal "VCC1")
		(22 "In10.Cu" signal "GND4")
		(24 "In11.Cu" signal "IN4")
		(26 "In12.Cu" signal "GND5")
		(28 "In13.Cu" signal "IN5")
		(30 "In14.Cu" signal "GND6")
		(32 "In15.Cu" signal "IN6")
		(34 "In16.Cu" signal "GND7")
		(2 "B.Cu" signal "BOTTOM")
		(9 "F.Adhes" user "F.Adhesive")
		(11 "B.Adhes" user "B.Adhesive")
		(13 "F.Paste" user "Package Geometry/Pastemask Top")
		(15 "B.Paste" user "Package Geometry/Pastemask Bottom")
		(5 "F.SilkS" user "Ref Des/Silkscreen Top")
		(7 "B.SilkS" user "Ref Des/Silkscreen Bottom")
		(1 "F.Mask" user "Board Geometry/Soldermask Top")
		(3 "B.Mask" user "Board Geometry/Soldermask Bottom")
		(17 "Dwgs.User" user "User.Drawings")
		(19 "Cmts.User" user "User.Comments")
		(21 "Eco1.User" user "User.Eco1")
		(23 "Eco2.User" user "User.Eco2")
		(25 "Edge.Cuts" user "Board Geometry/Outline")
		(27 "Margin" user)
		(31 "F.CrtYd" user "Package Geometry/Place Bound Top")
		(29 "B.CrtYd" user "Package Geometry/Place Bound Bottom")
		(35 "F.Fab" user "Ref Des/Assembly Top")
		(33 "B.Fab" user "Ref Des/Assembly Bottom")
	)
	(footprint ""
		(layer "B.Cu")
		(at 159.278574 -38.495986)
		(property "Reference" "C2315"
			(at 0 0 0)
			(layer "B.SilkS")
			(hide yes)
			(effects
				(font
					(size 1.27 1.27)
				)
				(justify mirror)
			)
		)
		(property "Value" ""
			(at 0 0 0)
			(layer "B.Fab")
			(effects
				(font
					(size 1.27 1.27)
				)
				(justify mirror)
			)
		)
		(duplicate_pad_numbers_are_jumpers no)
		(fp_line
			(start -0.7874 -0.4064)
			(end -0.7874 0.4064)
			(stroke
				(width 0.1524)
				(type default)
			)
			(layer "B.SilkS")
		)
		(fp_line
			(start -0.7874 0.4064)
			(end 0.7874 0.4064)
			(stroke
				(width 0.1524)
				(type default)
			)
			(layer "B.SilkS")
		)
		(fp_line
			(start 0.7874 -0.4064)
			(end -0.7874 -0.4064)
			(stroke
				(width 0.1524)
				(type default)
			)
			(layer "B.SilkS")
		)
		(fp_line
			(start 0.7874 0.4064)
			(end 0.7874 -0.4064)
			(stroke
				(width 0.1524)
				(type default)
			)
			(layer "B.SilkS")
		)
		(fp_line
			(start -0.67945 -0.3048)
			(end -0.67945 0.3048)
			(stroke
				(width 0.1)
				(type default)
			)
			(layer "B.Fab")
		)
		(fp_line
			(start -0.67945 0.3048)
			(end -0.120396 0.3048)
			(stroke
				(width 0.1)
				(type default)
			)
			(layer "B.Fab")
		)
		(fp_line
			(start -0.12065 -0.3048)
			(end -0.67945 -0.3048)
			(stroke
				(width 0.1)
				(type default)
			)
			(layer "B.Fab")
		)
		(fp_line
			(start -0.12065 -0.2794)
			(end -0.12065 -0.3048)
			(stroke
				(width 0.1)
				(type default)
			)
			(layer "B.Fab")
		)
		(fp_line
			(start -0.120396 0.2794)
			(end 0.12065 0.2794)
			(stroke
				(width 0.1)
				(type default)
			)
			(layer "B.Fab")
		)
		(fp_line
			(start -0.120396 0.3048)
			(end -0.120396 0.2794)
			(stroke
				(width 0.1)
				(type default)
			)
			(layer "B.Fab")
		)
		(fp_line
			(start 0.12065 -0.305054)
			(end 0.12065 -0.2794)
			(stroke
				(width 0.1)
				(type default)
			)
			(layer "B.Fab")
		)
		(fp_line
			(start 0.12065 -0.2794)
			(end -0.12065 -0.2794)
			(stroke
				(width 0.1)
				(type default)
			)
			(layer "B.Fab")
		)
		(fp_line
			(start 0.12065 0.2794)
			(end 0.12065 0.3048)
			(stroke
				(width 0.1)
				(type default)
			)
			(layer "B.Fab")
		)
		(fp_line
			(start 0.12065 0.3048)
			(end 0.67945 0.3048)
			(stroke
				(width 0.1)
				(type default)
			)
			(layer "B.Fab")
		)
		(fp_line
			(start 0.67945 -0.305054)
			(end 0.12065 -0.305054)
			(stroke
				(width 0.1)
				(type default)
			)
			(layer "B.Fab")
		)
		(fp_line
			(start 0.67945 0.3048)
			(end 0.67945 -0.305054)
			(stroke
				(width 0.1)
				(type default)
			)
			(layer "B.Fab")
		)
		(pad "1" smd circle
			(at 0.40005 0 180)
			(size 0 0)
			(layers "B.Cu" "B.Mask" "B.Paste")
			(net "P3V3_AUX_USB_HUB_2")
		)
		(pad "2" smd circle
			(at -0.40005 0 180)
			(size 0 0)
			(layers "B.Cu" "B.Mask" "B.Paste")
			(net "GND")
		)
	)
	(footprint ""
		(layer "B.Cu")
		(at 482.66985 2.372868 90)
		(property "Reference" "X24"
			(at 1.354328 3.30454 270)
			(unlocked yes)
			(layer "B.SilkS")
			(effects
				(font
					(size 0.7874 0.5842)
					(thickness 0.1524)
				)
				(justify left mirror)
			)
		)
		(property "Value" ""
			(at 0 0 90)
			(layer "B.Fab")
			(effects
				(font
					(size 1.27 1.27)
				)
				(justify mirror)
			)
		)
		(property "Device Type" "TP_TDR_4P_FTS_MPKT4_H025P0200_I"
			(at -1.30175 1.27 0)
			(unlocked yes)
			(layer "B.Fab")
			(hide yes)
			(effects
				(font
					(size 0.635 0.4064)
					(thickness 0.1524)
				)
				(justify mirror)
			)
		)
		(property "User Part Number" "TP15"
			(at -1.30175 1.27 0)
			(unlocked yes)
			(layer "Cmts.User")
			(hide yes)
			(effects
				(font
					(size 0.635 0.4064)
					(thickness 0.1524)
				)
				(justify mirror)
			)
		)
		(duplicate_pad_numbers_are_jumpers no)
		(fp_line
			(start 0 -1.27)
			(end 0 -0.635)
			(stroke
				(width 0.1524)
				(type default)
			)
			(layer "B.SilkS")
		)
		(fp_line
			(start -2.54 -1.27)
			(end 0 -1.27)
			(stroke
				(width 0.1524)
				(type default)
			)
			(layer "B.SilkS")
		)
		(fp_line
			(start -2.54 -1.1303)
			(end -2.54 -1.27)
			(stroke
				(width 0.1524)
				(type default)
			)
			(layer "B.SilkS")
		)
		(fp_line
			(start 0 0.635)
			(end 0 1.905)
			(stroke
				(width 0.1524)
				(type default)
			)
			(layer "B.SilkS")
		)
		(fp_line
			(start -2.54 1.4097)
			(end -2.54 1.1303)
			(stroke
				(width 0.1524)
				(type default)
			)
			(layer "B.SilkS")
		)
		(fp_line
			(start 0 3.175)
			(end 0 3.81)
			(stroke
				(width 0.1524)
				(type default)
			)
			(layer "B.SilkS")
		)
		(fp_line
			(start 0 3.81)
			(end -2.54 3.81)
			(stroke
				(width 0.1524)
				(type default)
			)
			(layer "B.SilkS")
		)
		(fp_line
			(start -2.54 3.81)
			(end -2.54 3.6703)
			(stroke
				(width 0.1524)
				(type default)
			)
			(layer "B.SilkS")
		)
		(fp_poly
			(pts
				(xy 2.285746 -0.762) (xy 2.285746 0.762) (xy 0.761746 0)
			)
			(stroke
				(width 0)
				(type default)
			)
			(fill yes)
			(layer "B.SilkS")
		)
		(fp_line
			(start 0 -1.27)
			(end 0 3.81)
			(stroke
				(width 0.1)
				(type default)
			)
			(layer "B.Fab")
		)
		(fp_line
			(start -2.54 -1.27)
			(end 0 -1.27)
			(stroke
				(width 0.1)
				(type default)
			)
			(layer "B.Fab")
		)
		(fp_line
			(start 0 3.81)
			(end -2.54 3.81)
			(stroke
				(width 0.1)
				(type default)
			)
			(layer "B.Fab")
		)
		(fp_line
			(start -2.54 3.81)
			(end -2.54 -1.27)
			(stroke
				(width 0.1)
				(type default)
			)
			(layer "B.Fab")
		)
		(fp_poly
			(pts
				(xy 0.761746 0) (xy 2.285746 -0.762) (xy 2.285746 0.762)
			)
			(stroke
				(width 0)
				(type default)
			)
			(fill yes)
			(layer "B.Fab")
		)
		(pad "1" thru_hole circle
			(at 0 0 270)
			(size 1.0033 1.0033)
			(drill 0.249936)
			(layers "*.Cu" "*.Mask")
			(remove_unused_layers no)
			(net "TDR_DIFF_100_BOT_DN")
			(clearance 0.10795)
			(padstack
				(mode front_inner_back)
				(layer "Inner"
					(shape circle)
					(size 0.8001 0.8001)
					(clearance 0.1524)
				)
				(layer "B.Cu"
					(shape circle)
					(size 1.0033 1.0033)
					(thermal_gap 0.10795)
					(clearance 0.10795)
				)
			)
		)
		(pad "2" thru_hole circle
			(at -2.54 0 270)
			(size 1.9939 1.9939)
			(drill 0.249936)
			(layers "*.Cu" "*.Mask")
			(remove_unused_layers no)
			(net "T1_GND")
			(clearance 0.10795)
			(padstack
				(mode front_inner_back)
				(layer "Inner"
					(shape circle)
					(size 0.8001 0.8001)
					(clearance 0.1524)
				)
				(layer "B.Cu"
					(shape circle)
					(size 1.9939 1.9939)
					(thermal_gap 0.10795)
					(clearance 0.10795)
				)
			)
		)
		(pad "3" thru_hole circle
			(at -2.54 2.54 270)
			(size 1.9939 1.9939)
			(drill 0.249936)
			(layers "*.Cu" "*.Mask")
			(remove_unused_layers no)
			(net "T1_GND")
			(clearance 0.10795)
			(padstack
				(mode front_inner_back)
				(layer "Inner"
					(shape circle)
					(size 0.8001 0.8001)
					(clearance 0.1524)
				)
				(layer "B.Cu"
					(shape circle)
					(size 1.9939 1.9939)
					(thermal_gap 0.10795)
					(clearance 0.10795)
				)
			)
		)
		(pad "4" thru_hole circle
			(at 0 2.54 270)
			(size 1.0033 1.0033)
			(drill 0.249936)
			(layers "*.Cu" "*.Mask")
			(remove_unused_layers no)
			(net "TDR_DIFF_100_BOT_DP")
			(clearance 0.10795)
			(padstack
				(mode front_inner_back)
				(layer "Inner"
					(shape circle)
					(size 0.8001 0.8001)
					(clearance 0.1524)
				)
				(layer "B.Cu"
					(shape circle)
					(size 1.0033 1.0033)
					(thermal_gap 0.10795)
					(clearance 0.10795)
				)
			)
		)
	)
)
